G04*
G04 #@! TF.GenerationSoftware,Altium Limited,Altium Designer,22.4.2 (48)*
G04*
G04 Layer_Color=32768*
%FSLAX25Y25*%
%MOIN*%
G70*
G04*
G04 #@! TF.SameCoordinates,446674BB-F454-490D-8607-5140536C8ADF*
G04*
G04*
G04 #@! TF.FilePolarity,Positive*
G04*
G01*
G75*
%ADD14C,0.00394*%
D14*
X148579Y-372099D02*
G03*
X134209Y-372099I-7185J0D01*
G01*
M02*
